# S9S_MB_2U (Grand Teton) — schematic netlist excerpt (pin names and nets, part order shuffled) for the footprints in the layout excerpt that follows; sources: Cadence DE-HDL packaged netlist, KiCad conversion of 03242023_DA0F0TMBIJ0_F0T_Motherboard_J_brd_V01_OCP.brd

C459  Q_CAP  47UF 4V 20% X6S  pkg C0805  page 79 : A = PVCCD_HV_CPU1 ; B = GND
C2318  Q_CAP  0.1UF 25V 10% EMPTY  pkg 0402  page 196 : A = P3V3_AUX_USB_HUB_2 ; B = GND
R3751  Q_RES  0 5% CHIP  pkg 0402LF  page 171 : A = INA230_2_A0 ; B = SMB_INA230_2_3V3AUX_SDA_R1

(kicad_pcb
	(version 20260206)
	(generator "pcbnew")
	(generator_version "10.0")
	(general
		(thickness 1.6)
		(legacy_teardrops no)
	)
	(paper "A4")
	(title_block
		(title "03242023_DA0F0TMBIJ0_F0T_Motherboard_J_brd_V01_OCP.brd")
		(comment 1 "Grand Teton / footprints 4474-4476 of 6105")
	)
	(layers
		(0 "F.Cu" signal "TOP")
		(4 "In1.Cu" signal "GND")
		(6 "In2.Cu" signal "IN1")
		(8 "In3.Cu" signal "GND1")
		(10 "In4.Cu" signal "IN2")
		(12 "In5.Cu" signal "GND2")
		(14 "In6.Cu" signal "IN3")
		(16 "In7.Cu" signal "GND3")
		(18 "In8.Cu" signal "VCC")
		(20 "In9.Cu" signal "VCC1")
		(22 "In10.Cu" signal "GND4")
		(24 "In11.Cu" signal "IN4")
		(26 "In12.Cu" signal "GND5")
		(28 "In13.Cu" signal "IN5")
		(30 "In14.Cu" signal "GND6")
		(32 "In15.Cu" signal "IN6")
		(34 "In16.Cu" signal "GND7")
		(2 "B.Cu" signal "BOTTOM")
		(9 "F.Adhes" user "F.Adhesive")
		(11 "B.Adhes" user "B.Adhesive")
		(13 "F.Paste" user "Package Geometry/Pastemask Top")
		(15 "B.Paste" user "Package Geometry/Pastemask Bottom")
		(5 "F.SilkS" user "Ref Des/Silkscreen Top")
		(7 "B.SilkS" user "Ref Des/Silkscreen Bottom")
		(1 "F.Mask" user "Board Geometry/Soldermask Top")
		(3 "B.Mask" user "Board Geometry/Soldermask Bottom")
		(17 "Dwgs.User" user "User.Drawings")
		(19 "Cmts.User" user "User.Comments")
		(21 "Eco1.User" user "User.Eco1")
		(23 "Eco2.User" user "User.Eco2")
		(25 "Edge.Cuts" user "Board Geometry/Outline")
		(27 "Margin" user)
		(31 "F.CrtYd" user "Package Geometry/Place Bound Top")
		(29 "B.CrtYd" user "Package Geometry/Place Bound Bottom")
		(35 "F.Fab" user "Ref Des/Assembly Top")
		(33 "B.Fab" user "Ref Des/Assembly Bottom")
	)
	(footprint ""
		(layer "B.Cu")
		(at 213.79688 -54.447948 90)
		(property "Reference" "R3751"
			(at 0 0 90)
			(layer "B.SilkS")
			(hide yes)
			(effects
				(font
					(size 1.27 1.27)
				)
				(justify mirror)
			)
		)
		(property "Value" ""
			(at 0 0 90)
			(layer "B.Fab")
			(effects
				(font
					(size 1.27 1.27)
				)
				(justify mirror)
			)
		)
		(duplicate_pad_numbers_are_jumpers no)
		(fp_line
			(start 0.7874 -0.4064)
			(end -0.7874 -0.4064)
			(stroke
				(width 0.1524)
				(type default)
			)
			(layer "B.SilkS")
		)
		(fp_line
			(start -0.7874 -0.4064)
			(end -0.7874 0.4064)
			(stroke
				(width 0.1524)
				(type default)
			)
			(layer "B.SilkS")
		)
		(fp_line
			(start 0.7874 0.4064)
			(end 0.7874 -0.4064)
			(stroke
				(width 0.1524)
				(type default)
			)
			(layer "B.SilkS")
		)
		(fp_line
			(start -0.7874 0.4064)
			(end 0.7874 0.4064)
			(stroke
				(width 0.1524)
				(type default)
			)
			(layer "B.SilkS")
		)
		(fp_line
			(start 0.67945 -0.305054)
			(end 0.12065 -0.305054)
			(stroke
				(width 0.1)
				(type default)
			)
			(layer "B.Fab")
		)
		(fp_line
			(start 0.12065 -0.305054)
			(end 0.12065 -0.2794)
			(stroke
				(width 0.1)
				(type default)
			)
			(layer "B.Fab")
		)
		(fp_line
			(start -0.12065 -0.3048)
			(end -0.67945 -0.3048)
			(stroke
				(width 0.1)
				(type default)
			)
			(layer "B.Fab")
		)
		(fp_line
			(start -0.67945 -0.3048)
			(end -0.67945 0.3048)
			(stroke
				(width 0.1)
				(type default)
			)
			(layer "B.Fab")
		)
		(fp_line
			(start 0.12065 -0.2794)
			(end -0.12065 -0.2794)
			(stroke
				(width 0.1)
				(type default)
			)
			(layer "B.Fab")
		)
		(fp_line
			(start -0.12065 -0.2794)
			(end -0.12065 -0.3048)
			(stroke
				(width 0.1)
				(type default)
			)
			(layer "B.Fab")
		)
		(fp_line
			(start 0.12065 0.2794)
			(end 0.12065 0.3048)
			(stroke
				(width 0.1)
				(type default)
			)
			(layer "B.Fab")
		)
		(fp_line
			(start -0.120396 0.2794)
			(end 0.12065 0.2794)
			(stroke
				(width 0.1)
				(type default)
			)
			(layer "B.Fab")
		)
		(fp_line
			(start 0.67945 0.3048)
			(end 0.67945 -0.305054)
			(stroke
				(width 0.1)
				(type default)
			)
			(layer "B.Fab")
		)
		(fp_line
			(start 0.12065 0.3048)
			(end 0.67945 0.3048)
			(stroke
				(width 0.1)
				(type default)
			)
			(layer "B.Fab")
		)
		(fp_line
			(start -0.120396 0.3048)
			(end -0.120396 0.2794)
			(stroke
				(width 0.1)
				(type default)
			)
			(layer "B.Fab")
		)
		(fp_line
			(start -0.67945 0.3048)
			(end -0.120396 0.3048)
			(stroke
				(width 0.1)
				(type default)
			)
			(layer "B.Fab")
		)
		(pad "1" smd circle
			(at 0.40005 0 270)
			(size 0 0)
			(layers "B.Cu" "B.Mask" "B.Paste")
			(net "INA230_2_A0")
		)
		(pad "2" smd circle
			(at -0.40005 0 270)
			(size 0 0)
			(layers "B.Cu" "B.Mask" "B.Paste")
			(net "SMB_INA230_2_3V3AUX_SDA_R1")
		)
	)
	(footprint ""
		(layer "B.Cu")
		(at 156.720032 -39.8653 90)
		(property "Reference" "C2318"
			(at 0 0 90)
			(layer "B.SilkS")
			(hide yes)
			(effects
				(font
					(size 1.27 1.27)
				)
				(justify mirror)
			)
		)
		(property "Value" ""
			(at 0 0 90)
			(layer "B.Fab")
			(effects
				(font
					(size 1.27 1.27)
				)
				(justify mirror)
			)
		)
		(duplicate_pad_numbers_are_jumpers no)
		(fp_line
			(start 0.7874 -0.4064)
			(end -0.7874 -0.4064)
			(stroke
				(width 0.1524)
				(type default)
			)
			(layer "B.SilkS")
		)
		(fp_line
			(start -0.7874 -0.4064)
			(end -0.7874 0.4064)
			(stroke
				(width 0.1524)
				(type default)
			)
			(layer "B.SilkS")
		)
		(fp_line
			(start 0.7874 0.4064)
			(end 0.7874 -0.4064)
			(stroke
				(width 0.1524)
				(type default)
			)
			(layer "B.SilkS")
		)
		(fp_line
			(start -0.7874 0.4064)
			(end 0.7874 0.4064)
			(stroke
				(width 0.1524)
				(type default)
			)
			(layer "B.SilkS")
		)
		(fp_line
			(start 0.67945 -0.305054)
			(end 0.12065 -0.305054)
			(stroke
				(width 0.1)
				(type default)
			)
			(layer "B.Fab")
		)
		(fp_line
			(start 0.12065 -0.305054)
			(end 0.12065 -0.2794)
			(stroke
				(width 0.1)
				(type default)
			)
			(layer "B.Fab")
		)
		(fp_line
			(start -0.12065 -0.3048)
			(end -0.67945 -0.3048)
			(stroke
				(width 0.1)
				(type default)
			)
			(layer "B.Fab")
		)
		(fp_line
			(start -0.67945 -0.3048)
			(end -0.67945 0.3048)
			(stroke
				(width 0.1)
				(type default)
			)
			(layer "B.Fab")
		)
		(fp_line
			(start 0.12065 -0.2794)
			(end -0.12065 -0.2794)
			(stroke
				(width 0.1)
				(type default)
			)
			(layer "B.Fab")
		)
		(fp_line
			(start -0.12065 -0.2794)
			(end -0.12065 -0.3048)
			(stroke
				(width 0.1)
				(type default)
			)
			(layer "B.Fab")
		)
		(fp_line
			(start 0.12065 0.2794)
			(end 0.12065 0.3048)
			(stroke
				(width 0.1)
				(type default)
			)
			(layer "B.Fab")
		)
		(fp_line
			(start -0.120396 0.2794)
			(end 0.12065 0.2794)
			(stroke
				(width 0.1)
				(type default)
			)
			(layer "B.Fab")
		)
		(fp_line
			(start 0.67945 0.3048)
			(end 0.67945 -0.305054)
			(stroke
				(width 0.1)
				(type default)
			)
			(layer "B.Fab")
		)
		(fp_line
			(start 0.12065 0.3048)
			(end 0.67945 0.3048)
			(stroke
				(width 0.1)
				(type default)
			)
			(layer "B.Fab")
		)
		(fp_line
			(start -0.120396 0.3048)
			(end -0.120396 0.2794)
			(stroke
				(width 0.1)
				(type default)
			)
			(layer "B.Fab")
		)
		(fp_line
			(start -0.67945 0.3048)
			(end -0.120396 0.3048)
			(stroke
				(width 0.1)
				(type default)
			)
			(layer "B.Fab")
		)
		(pad "1" smd circle
			(at 0.40005 0 270)
			(size 0 0)
			(layers "B.Cu" "B.Mask" "B.Paste")
			(net "P3V3_AUX_USB_HUB_2")
		)
		(pad "2" smd circle
			(at -0.40005 0 270)
			(size 0 0)
			(layers "B.Cu" "B.Mask" "B.Paste")
			(net "GND")
		)
	)
	(footprint ""
		(layer "B.Cu")
		(at 114.734848 -210.194144 180)
		(property "Reference" "C459"
			(at 0 0 0)
			(layer "B.SilkS")
			(hide yes)
			(effects
				(font
					(size 1.27 1.27)
				)
				(justify mirror)
			)
		)
		(property "Value" ""
			(at 0 0 0)
			(layer "B.Fab")
			(effects
				(font
					(size 1.27 1.27)
				)
				(justify mirror)
			)
		)
		(duplicate_pad_numbers_are_jumpers no)
		(fp_line
			(start 1.524 0.762)
			(end 1.524 -0.762)
			(stroke
				(width 0.1524)
				(type default)
			)
			(layer "B.SilkS")
		)
		(fp_line
			(start 1.524 -0.762)
			(end -1.524 -0.762)
			(stroke
				(width 0.1524)
				(type default)
			)
			(layer "B.SilkS")
		)
		(fp_line
			(start -1.524 0.762)
			(end 1.524 0.762)
			(stroke
				(width 0.1524)
				(type default)
			)
			(layer "B.SilkS")
		)
		(fp_line
			(start -1.524 -0.762)
			(end -1.524 0.762)
			(stroke
				(width 0.1524)
				(type default)
			)
			(layer "B.SilkS")
		)
		(fp_line
			(start 1.1049 0.724916)
			(end -1.1049 0.724916)
			(stroke
				(width 0.1)
				(type default)
			)
			(layer "B.Fab")
		)
		(fp_line
			(start 1.1049 -0.724916)
			(end 1.1049 0.724916)
			(stroke
				(width 0.1)
				(type default)
			)
			(layer "B.Fab")
		)
		(fp_line
			(start -1.1049 0.724916)
			(end -1.1049 -0.724916)
			(stroke
				(width 0.1)
				(type default)
			)
			(layer "B.Fab")
		)
		(fp_line
			(start -1.1049 -0.724916)
			(end 1.1049 -0.724916)
			(stroke
				(width 0.1)
				(type default)
			)
			(layer "B.Fab")
		)
		(pad "1" smd rect
			(at 0.889 0 180)
			(size 1.016 1.27)
			(layers "B.Cu" "B.Mask" "B.Paste")
			(net "PVCCD_HV_CPU1")
		)
		(pad "2" smd rect
			(at -0.889 0 180)
			(size 1.016 1.27)
			(layers "B.Cu" "B.Mask" "B.Paste")
			(net "GND")
		)
	)
)
